# S9S_MB_2U (Grand Teton) — schematic netlist excerpt (pin names and nets, part order shuffled) for the footprints in the layout excerpt that follows; sources: Cadence DE-HDL packaged netlist, KiCad conversion of 03242023_DA0F0TMBIJ0_F0T_Motherboard_J_brd_V01_OCP.brd

C613  Q_CAP  1UF 25V 10% EMPTY  pkg C0402  page 130 : A = RST_PLD_CPU1_DRAM_GH_N ; B = GND
C1146  Q_CAP  0.01UF 50V 10% X7R  pkg C0402  page 217 : A = P3V3_AUX_FPGA_VCCIO2 ; B = GND

(kicad_pcb
	(version 20260206)
	(generator "pcbnew")
	(generator_version "10.0")
	(general
		(thickness 1.6)
		(legacy_teardrops no)
	)
	(paper "A4")
	(title_block
		(title "03242023_DA0F0TMBIJ0_F0T_Motherboard_J_brd_V01_OCP.brd")
		(comment 1 "Grand Teton / footprints 5125-5126 of 6105")
	)
	(layers
		(0 "F.Cu" signal "TOP")
		(4 "In1.Cu" signal "GND")
		(6 "In2.Cu" signal "IN1")
		(8 "In3.Cu" signal "GND1")
		(10 "In4.Cu" signal "IN2")
		(12 "In5.Cu" signal "GND2")
		(14 "In6.Cu" signal "IN3")
		(16 "In7.Cu" signal "GND3")
		(18 "In8.Cu" signal "VCC")
		(20 "In9.Cu" signal "VCC1")
		(22 "In10.Cu" signal "GND4")
		(24 "In11.Cu" signal "IN4")
		(26 "In12.Cu" signal "GND5")
		(28 "In13.Cu" signal "IN5")
		(30 "In14.Cu" signal "GND6")
		(32 "In15.Cu" signal "IN6")
		(34 "In16.Cu" signal "GND7")
		(2 "B.Cu" signal "BOTTOM")
		(9 "F.Adhes" user "F.Adhesive")
		(11 "B.Adhes" user "B.Adhesive")
		(13 "F.Paste" user "Package Geometry/Pastemask Top")
		(15 "B.Paste" user "Package Geometry/Pastemask Bottom")
		(5 "F.SilkS" user "Ref Des/Silkscreen Top")
		(7 "B.SilkS" user "Ref Des/Silkscreen Bottom")
		(1 "F.Mask" user "Board Geometry/Soldermask Top")
		(3 "B.Mask" user "Board Geometry/Soldermask Bottom")
		(17 "Dwgs.User" user "User.Drawings")
		(19 "Cmts.User" user "User.Comments")
		(21 "Eco1.User" user "User.Eco1")
		(23 "Eco2.User" user "User.Eco2")
		(25 "Edge.Cuts" user "Board Geometry/Outline")
		(27 "Margin" user)
		(31 "F.CrtYd" user "Package Geometry/Place Bound Top")
		(29 "B.CrtYd" user "Package Geometry/Place Bound Bottom")
		(35 "F.Fab" user "Ref Des/Assembly Top")
		(33 "B.Fab" user "Ref Des/Assembly Bottom")
	)
	(footprint ""
		(layer "B.Cu")
		(at 181.755542 -113.77549)
		(property "Reference" "C1146"
			(at 0 0 0)
			(layer "B.SilkS")
			(hide yes)
			(effects
				(font
					(size 1.27 1.27)
				)
				(justify mirror)
			)
		)
		(property "Value" ""
			(at 0 0 0)
			(layer "B.Fab")
			(effects
				(font
					(size 1.27 1.27)
				)
				(justify mirror)
			)
		)
		(duplicate_pad_numbers_are_jumpers no)
		(fp_line
			(start -0.69215 -0.2921)
			(end -0.69215 0.2921)
			(stroke
				(width 0.1524)
				(type default)
			)
			(layer "B.SilkS")
		)
		(fp_line
			(start -0.69215 0.2921)
			(end 0.69215 0.2921)
			(stroke
				(width 0.1524)
				(type default)
			)
			(layer "B.SilkS")
		)
		(fp_line
			(start 0.69215 -0.2921)
			(end -0.69215 -0.2921)
			(stroke
				(width 0.1524)
				(type default)
			)
			(layer "B.SilkS")
		)
		(fp_line
			(start 0.69215 0.2921)
			(end 0.69215 -0.2921)
			(stroke
				(width 0.1524)
				(type default)
			)
			(layer "B.SilkS")
		)
		(fp_line
			(start -0.51435 -0.2794)
			(end -0.51435 0.2794)
			(stroke
				(width 0.1)
				(type default)
			)
			(layer "B.Fab")
		)
		(fp_line
			(start -0.51435 0.2794)
			(end 0.51435 0.2794)
			(stroke
				(width 0.1)
				(type default)
			)
			(layer "B.Fab")
		)
		(fp_line
			(start 0.51435 -0.2794)
			(end -0.51435 -0.2794)
			(stroke
				(width 0.1)
				(type default)
			)
			(layer "B.Fab")
		)
		(fp_line
			(start 0.51435 0.2794)
			(end 0.51435 -0.2794)
			(stroke
				(width 0.1)
				(type default)
			)
			(layer "B.Fab")
		)
		(pad "1" smd circle
			(at 0.40005 0 180)
			(size 0 0)
			(layers "B.Cu" "B.Mask" "B.Paste")
			(net "P3V3_AUX_FPGA_VCCIO2")
		)
		(pad "2" smd circle
			(at -0.40005 0 180)
			(size 0 0)
			(layers "B.Cu" "B.Mask" "B.Paste")
			(net "GND")
		)
		(zone
			(layer "B.Cu")
			(hatch none 0.5)
			(connect_pads
				(clearance 0)
			)
			(min_thickness 0.25)
			(keepout
				(tracks not_allowed)
				(vias allowed)
				(pads allowed)
				(copperpour not_allowed)
				(footprints allowed)
			)
			(placement
				(enabled no)
				(sheetname "")
			)
			(fill
				(thermal_gap 0.5)
				(thermal_bridge_width 0.5)
				(island_removal_mode 0)
			)
			(polygon
				(pts
					(xy 181.946042 -113.68786) (xy 181.854602 -113.629694) (xy 181.655212 -113.629694) (xy 181.565042 -113.68786)
					(xy 181.565042 -113.86312) (xy 181.655212 -113.92154) (xy 181.854602 -113.92154) (xy 181.946042 -113.863374)
				)
			)
		)
	)
	(footprint ""
		(layer "B.Cu")
		(at 191.264286 -193.615056 -90)
		(property "Reference" "C613"
			(at 0 0 90)
			(layer "B.SilkS")
			(hide yes)
			(effects
				(font
					(size 1.27 1.27)
				)
				(justify mirror)
			)
		)
		(property "Value" ""
			(at 0 0 90)
			(layer "B.Fab")
			(effects
				(font
					(size 1.27 1.27)
				)
				(justify mirror)
			)
		)
		(duplicate_pad_numbers_are_jumpers no)
		(fp_line
			(start -0.7874 0.4064)
			(end 0.7874 0.4064)
			(stroke
				(width 0.1524)
				(type default)
			)
			(layer "B.SilkS")
		)
		(fp_line
			(start 0.7874 0.4064)
			(end 0.7874 -0.4064)
			(stroke
				(width 0.1524)
				(type default)
			)
			(layer "B.SilkS")
		)
		(fp_line
			(start -0.7874 -0.4064)
			(end -0.7874 0.4064)
			(stroke
				(width 0.1524)
				(type default)
			)
			(layer "B.SilkS")
		)
		(fp_line
			(start 0.7874 -0.4064)
			(end -0.7874 -0.4064)
			(stroke
				(width 0.1524)
				(type default)
			)
			(layer "B.SilkS")
		)
		(fp_line
			(start -0.67945 0.3048)
			(end -0.120396 0.3048)
			(stroke
				(width 0.1)
				(type default)
			)
			(layer "B.Fab")
		)
		(fp_line
			(start -0.120396 0.3048)
			(end -0.120396 0.2794)
			(stroke
				(width 0.1)
				(type default)
			)
			(layer "B.Fab")
		)
		(fp_line
			(start 0.12065 0.3048)
			(end 0.67945 0.3048)
			(stroke
				(width 0.1)
				(type default)
			)
			(layer "B.Fab")
		)
		(fp_line
			(start 0.67945 0.3048)
			(end 0.67945 -0.305054)
			(stroke
				(width 0.1)
				(type default)
			)
			(layer "B.Fab")
		)
		(fp_line
			(start -0.120396 0.2794)
			(end 0.12065 0.2794)
			(stroke
				(width 0.1)
				(type default)
			)
			(layer "B.Fab")
		)
		(fp_line
			(start 0.12065 0.2794)
			(end 0.12065 0.3048)
			(stroke
				(width 0.1)
				(type default)
			)
			(layer "B.Fab")
		)
		(fp_line
			(start -0.12065 -0.2794)
			(end -0.12065 -0.3048)
			(stroke
				(width 0.1)
				(type default)
			)
			(layer "B.Fab")
		)
		(fp_line
			(start 0.12065 -0.2794)
			(end -0.12065 -0.2794)
			(stroke
				(width 0.1)
				(type default)
			)
			(layer "B.Fab")
		)
		(fp_line
			(start -0.67945 -0.3048)
			(end -0.67945 0.3048)
			(stroke
				(width 0.1)
				(type default)
			)
			(layer "B.Fab")
		)
		(fp_line
			(start -0.12065 -0.3048)
			(end -0.67945 -0.3048)
			(stroke
				(width 0.1)
				(type default)
			)
			(layer "B.Fab")
		)
		(fp_line
			(start 0.12065 -0.305054)
			(end 0.12065 -0.2794)
			(stroke
				(width 0.1)
				(type default)
			)
			(layer "B.Fab")
		)
		(fp_line
			(start 0.67945 -0.305054)
			(end 0.12065 -0.305054)
			(stroke
				(width 0.1)
				(type default)
			)
			(layer "B.Fab")
		)
		(pad "1" smd circle
			(at 0.40005 0 90)
			(size 0 0)
			(layers "B.Cu" "B.Mask" "B.Paste")
			(net "RST_PLD_CPU1_DRAM_GH_N")
		)
		(pad "2" smd circle
			(at -0.40005 0 90)
			(size 0 0)
			(layers "B.Cu" "B.Mask" "B.Paste")
			(net "GND")
		)
	)
)
